(kicad_pcb
	(version 20260206)
	(generator "pcbnew")
	(generator_version "10.0")
	(general
		(thickness 1.6)
		(legacy_teardrops no)
	)
	(paper "A4")
	(title_block
		(title "03242023_DA0F0TMBIJ0_F0T_Motherboard_J_brd_V01_OCP.brd")
		(comment 1 "Grand Teton / footprint 2874 of 6105 (J29), pads 225-291 of 291")
	)
	(layers
		(0 "F.Cu" signal "TOP")
		(4 "In1.Cu" signal "GND")
		(6 "In2.Cu" signal "IN1")
		(8 "In3.Cu" signal "GND1")
		(10 "In4.Cu" signal "IN2")
		(12 "In5.Cu" signal "GND2")
		(14 "In6.Cu" signal "IN3")
		(16 "In7.Cu" signal "GND3")
		(18 "In8.Cu" signal "VCC")
		(20 "In9.Cu" signal "VCC1")
		(22 "In10.Cu" signal "GND4")
		(24 "In11.Cu" signal "IN4")
		(26 "In12.Cu" signal "GND5")
		(28 "In13.Cu" signal "IN5")
		(30 "In14.Cu" signal "GND6")
		(32 "In15.Cu" signal "IN6")
		(34 "In16.Cu" signal "GND7")
		(2 "B.Cu" signal "BOTTOM")
		(9 "F.Adhes" user "F.Adhesive")
		(11 "B.Adhes" user "B.Adhesive")
		(13 "F.Paste" user "Package Geometry/Pastemask Top")
		(15 "B.Paste" user "Package Geometry/Pastemask Bottom")
		(5 "F.SilkS" user "Ref Des/Silkscreen Top")
		(7 "B.SilkS" user "Ref Des/Silkscreen Bottom")
		(1 "F.Mask" user "Board Geometry/Soldermask Top")
		(3 "B.Mask" user "Board Geometry/Soldermask Bottom")
		(17 "Dwgs.User" user "User.Drawings")
		(19 "Cmts.User" user "User.Comments")
		(21 "Eco1.User" user "User.Eco1")
		(23 "Eco2.User" user "User.Eco2")
		(25 "Edge.Cuts" user "Board Geometry/Outline")
		(27 "Margin" user)
		(31 "F.CrtYd" user "Package Geometry/Place Bound Top")
		(29 "B.CrtYd" user "Package Geometry/Place Bound Bottom")
		(35 "F.Fab" user "Ref Des/Assembly Top")
		(33 "B.Fab" user "Ref Des/Assembly Bottom")
	)
	(footprint ""
		(layer "F.Cu")
		(at 198.58228 -258.091686)
		(property "Reference" "J29"
			(at -3.683 -81.702148 0)
			(unlocked yes)
			(layer "F.SilkS")
			(effects
				(font
					(size 0.7874 0.5842)
					(thickness 0.1524)
				)
				(justify left)
			)
		)
		(property "Value" ""
			(at 0 0 0)
			(layer "F.Fab")
			(effects
				(font
					(size 1.27 1.27)
				)
			)
		)
		(duplicate_pad_numbers_are_jumpers no)
		(pad "225" smd rect
			(at 2.050034 9.774936 270)
			(size 0.519938 1.4986)
			(layers "F.Cu" "F.Mask" "F.Paste")
			(net "M_G_CPU1_SB_CA<5>")
		)
		(pad "226" smd rect
			(at 2.050034 10.625074 270)
			(size 0.519938 1.4986)
			(layers "F.Cu" "F.Mask" "F.Paste")
			(net "GND")
		)
		(pad "227" smd rect
			(at 2.050034 11.474958 270)
			(size 0.519938 1.4986)
			(layers "F.Cu" "F.Mask" "F.Paste")
			(net "M_G_CPU1_SB_PAR")
		)
		(pad "228" smd rect
			(at 2.050034 12.325096 270)
			(size 0.519938 1.4986)
			(layers "F.Cu" "F.Mask" "F.Paste")
			(net "GND")
		)
		(pad "229" smd rect
			(at 2.050034 13.17498 270)
			(size 0.519938 1.4986)
			(layers "F.Cu" "F.Mask" "F.Paste")
			(net "M_G_CPU1_SB_CS_N<1>")
		)
		(pad "230" smd rect
			(at 2.050034 14.025118 270)
			(size 0.519938 1.4986)
			(layers "F.Cu" "F.Mask" "F.Paste")
			(net "GND")
		)
		(pad "231" smd rect
			(at 2.050034 14.875002 270)
			(size 0.519938 1.4986)
			(layers "F.Cu" "F.Mask" "F.Paste")
			(net "TP_CHG_CPU1_DIMM1_FRU_5")
		)
		(pad "232" smd rect
			(at 2.050034 15.724886 270)
			(size 0.519938 1.4986)
			(layers "F.Cu" "F.Mask" "F.Paste")
			(net "TP_CHG_CPU1_DIMM1_FRU_6")
		)
		(pad "233" smd rect
			(at 2.050034 16.575024 270)
			(size 0.519938 1.4986)
			(layers "F.Cu" "F.Mask" "F.Paste")
			(net "GND")
		)
		(pad "234" smd rect
			(at 2.050034 17.424908 270)
			(size 0.519938 1.4986)
			(layers "F.Cu" "F.Mask" "F.Paste")
			(net "M_G_CPU1_SB_CB<6>")
		)
		(pad "235" smd rect
			(at 2.050034 18.275046 270)
			(size 0.519938 1.4986)
			(layers "F.Cu" "F.Mask" "F.Paste")
			(net "GND")
		)
		(pad "236" smd rect
			(at 2.050034 19.12493 270)
			(size 0.519938 1.4986)
			(layers "F.Cu" "F.Mask" "F.Paste")
			(net "M_G_CPU1_SB_CB<7>")
		)
		(pad "237" smd rect
			(at 2.050034 19.975068 270)
			(size 0.519938 1.4986)
			(layers "F.Cu" "F.Mask" "F.Paste")
			(net "GND")
		)
		(pad "238" smd rect
			(at 2.050034 20.824952 270)
			(size 0.519938 1.4986)
			(layers "F.Cu" "F.Mask" "F.Paste")
			(net "M_G_CPU1_SB_DQS_DN<4>")
		)
		(pad "239" smd rect
			(at 2.050034 21.67509 270)
			(size 0.519938 1.4986)
			(layers "F.Cu" "F.Mask" "F.Paste")
			(net "M_G_CPU1_SB_DQS_DP<4>")
		)
		(pad "240" smd rect
			(at 2.050034 22.524974 270)
			(size 0.519938 1.4986)
			(layers "F.Cu" "F.Mask" "F.Paste")
			(net "GND")
		)
		(pad "241" smd rect
			(at 2.050034 23.375112 270)
			(size 0.519938 1.4986)
			(layers "F.Cu" "F.Mask" "F.Paste")
			(net "M_G_CPU1_SB_CB<2>")
		)
		(pad "242" smd rect
			(at 2.050034 24.224996 270)
			(size 0.519938 1.4986)
			(layers "F.Cu" "F.Mask" "F.Paste")
			(net "GND")
		)
		(pad "243" smd rect
			(at 2.050034 25.07488 270)
			(size 0.519938 1.4986)
			(layers "F.Cu" "F.Mask" "F.Paste")
			(net "M_G_CPU1_SB_CB<3>")
		)
		(pad "244" smd rect
			(at 2.050034 25.925018 270)
			(size 0.519938 1.4986)
			(layers "F.Cu" "F.Mask" "F.Paste")
			(net "GND")
		)
		(pad "245" smd rect
			(at 2.050034 26.774902 270)
			(size 0.519938 1.4986)
			(layers "F.Cu" "F.Mask" "F.Paste")
			(net "M_G_CPU1_SB_DQ<2>")
		)
		(pad "246" smd rect
			(at 2.050034 27.62504 270)
			(size 0.519938 1.4986)
			(layers "F.Cu" "F.Mask" "F.Paste")
			(net "GND")
		)
		(pad "247" smd rect
			(at 2.050034 28.474924 270)
			(size 0.519938 1.4986)
			(layers "F.Cu" "F.Mask" "F.Paste")
			(net "M_G_CPU1_SB_DQ<3>")
		)
		(pad "248" smd rect
			(at 2.050034 29.325062 270)
			(size 0.519938 1.4986)
			(layers "F.Cu" "F.Mask" "F.Paste")
			(net "GND")
		)
		(pad "249" smd rect
			(at 2.050034 30.174946 270)
			(size 0.519938 1.4986)
			(layers "F.Cu" "F.Mask" "F.Paste")
			(net "M_G_CPU1_SB_DQS_DN<5>")
		)
		(pad "250" smd rect
			(at 2.050034 31.025084 270)
			(size 0.519938 1.4986)
			(layers "F.Cu" "F.Mask" "F.Paste")
			(net "M_G_CPU1_SB_DQS_DP<5>")
		)
		(pad "251" smd rect
			(at 2.050034 31.874968 270)
			(size 0.519938 1.4986)
			(layers "F.Cu" "F.Mask" "F.Paste")
			(net "GND")
		)
		(pad "252" smd rect
			(at 2.050034 32.725106 270)
			(size 0.519938 1.4986)
			(layers "F.Cu" "F.Mask" "F.Paste")
			(net "M_G_CPU1_SB_DQ<6>")
		)
		(pad "253" smd rect
			(at 2.050034 33.57499 270)
			(size 0.519938 1.4986)
			(layers "F.Cu" "F.Mask" "F.Paste")
			(net "GND")
		)
		(pad "254" smd rect
			(at 2.050034 34.425128 270)
			(size 0.519938 1.4986)
			(layers "F.Cu" "F.Mask" "F.Paste")
			(net "M_G_CPU1_SB_DQ<7>")
		)
		(pad "255" smd rect
			(at 2.050034 35.275012 270)
			(size 0.519938 1.4986)
			(layers "F.Cu" "F.Mask" "F.Paste")
			(net "GND")
		)
		(pad "256" smd rect
			(at 2.050034 36.124896 270)
			(size 0.519938 1.4986)
			(layers "F.Cu" "F.Mask" "F.Paste")
			(net "M_G_CPU1_SB_DQ<10>")
		)
		(pad "257" smd rect
			(at 2.050034 36.975034 270)
			(size 0.519938 1.4986)
			(layers "F.Cu" "F.Mask" "F.Paste")
			(net "GND")
		)
		(pad "258" smd rect
			(at 2.050034 37.824918 270)
			(size 0.519938 1.4986)
			(layers "F.Cu" "F.Mask" "F.Paste")
			(net "M_G_CPU1_SB_DQ<11>")
		)
		(pad "259" smd rect
			(at 2.050034 38.675056 270)
			(size 0.519938 1.4986)
			(layers "F.Cu" "F.Mask" "F.Paste")
			(net "GND")
		)
		(pad "260" smd rect
			(at 2.050034 39.52494 270)
			(size 0.519938 1.4986)
			(layers "F.Cu" "F.Mask" "F.Paste")
			(net "M_G_CPU1_SB_DQS_DN<6>")
		)
		(pad "261" smd rect
			(at 2.050034 40.375078 270)
			(size 0.519938 1.4986)
			(layers "F.Cu" "F.Mask" "F.Paste")
			(net "M_G_CPU1_SB_DQS_DP<6>")
		)
		(pad "262" smd rect
			(at 2.050034 41.224962 270)
			(size 0.519938 1.4986)
			(layers "F.Cu" "F.Mask" "F.Paste")
			(net "GND")
		)
		(pad "263" smd rect
			(at 2.050034 42.0751 270)
			(size 0.519938 1.4986)
			(layers "F.Cu" "F.Mask" "F.Paste")
			(net "M_G_CPU1_SB_DQ<14>")
		)
		(pad "264" smd rect
			(at 2.050034 42.924984 270)
			(size 0.519938 1.4986)
			(layers "F.Cu" "F.Mask" "F.Paste")
			(net "GND")
		)
		(pad "265" smd rect
			(at 2.050034 43.775122 270)
			(size 0.519938 1.4986)
			(layers "F.Cu" "F.Mask" "F.Paste")
			(net "M_G_CPU1_SB_DQ<15>")
		)
		(pad "266" smd rect
			(at 2.050034 44.625006 270)
			(size 0.519938 1.4986)
			(layers "F.Cu" "F.Mask" "F.Paste")
			(net "GND")
		)
		(pad "267" smd rect
			(at 2.050034 45.47489 270)
			(size 0.519938 1.4986)
			(layers "F.Cu" "F.Mask" "F.Paste")
			(net "M_G_CPU1_SB_DQ<18>")
		)
		(pad "268" smd rect
			(at 2.050034 46.325028 270)
			(size 0.519938 1.4986)
			(layers "F.Cu" "F.Mask" "F.Paste")
			(net "GND")
		)
		(pad "269" smd rect
			(at 2.050034 47.174912 270)
			(size 0.519938 1.4986)
			(layers "F.Cu" "F.Mask" "F.Paste")
			(net "M_G_CPU1_SB_DQ<19>")
		)
		(pad "270" smd rect
			(at 2.050034 48.02505 270)
			(size 0.519938 1.4986)
			(layers "F.Cu" "F.Mask" "F.Paste")
			(net "GND")
		)
		(pad "271" smd rect
			(at 2.050034 48.874934 270)
			(size 0.519938 1.4986)
			(layers "F.Cu" "F.Mask" "F.Paste")
			(net "M_G_CPU1_SB_DQS_DN<7>")
		)
		(pad "272" smd rect
			(at 2.050034 49.725072 270)
			(size 0.519938 1.4986)
			(layers "F.Cu" "F.Mask" "F.Paste")
			(net "M_G_CPU1_SB_DQS_DP<7>")
		)
		(pad "273" smd rect
			(at 2.050034 50.574956 270)
			(size 0.519938 1.4986)
			(layers "F.Cu" "F.Mask" "F.Paste")
			(net "GND")
		)
		(pad "274" smd rect
			(at 2.050034 51.425094 270)
			(size 0.519938 1.4986)
			(layers "F.Cu" "F.Mask" "F.Paste")
			(net "M_G_CPU1_SB_DQ<22>")
		)
		(pad "275" smd rect
			(at 2.050034 52.274978 270)
			(size 0.519938 1.4986)
			(layers "F.Cu" "F.Mask" "F.Paste")
			(net "GND")
		)
		(pad "276" smd rect
			(at 2.050034 53.125116 270)
			(size 0.519938 1.4986)
			(layers "F.Cu" "F.Mask" "F.Paste")
			(net "M_G_CPU1_SB_DQ<23>")
		)
		(pad "277" smd rect
			(at 2.050034 53.975 270)
			(size 0.519938 1.4986)
			(layers "F.Cu" "F.Mask" "F.Paste")
			(net "GND")
		)
		(pad "278" smd rect
			(at 2.050034 54.824884 270)
			(size 0.519938 1.4986)
			(layers "F.Cu" "F.Mask" "F.Paste")
			(net "M_G_CPU1_SB_DQ<26>")
		)
		(pad "279" smd rect
			(at 2.050034 55.675022 270)
			(size 0.519938 1.4986)
			(layers "F.Cu" "F.Mask" "F.Paste")
			(net "GND")
		)
		(pad "280" smd rect
			(at 2.050034 56.524906 270)
			(size 0.519938 1.4986)
			(layers "F.Cu" "F.Mask" "F.Paste")
			(net "M_G_CPU1_SB_DQ<27>")
		)
		(pad "281" smd rect
			(at 2.050034 57.375044 270)
			(size 0.519938 1.4986)
			(layers "F.Cu" "F.Mask" "F.Paste")
			(net "GND")
		)
		(pad "282" smd rect
			(at 2.050034 58.224928 270)
			(size 0.519938 1.4986)
			(layers "F.Cu" "F.Mask" "F.Paste")
			(net "M_G_CPU1_SB_DQS_DN<8>")
		)
		(pad "283" smd rect
			(at 2.050034 59.075066 270)
			(size 0.519938 1.4986)
			(layers "F.Cu" "F.Mask" "F.Paste")
			(net "M_G_CPU1_SB_DQS_DP<8>")
		)
		(pad "284" smd rect
			(at 2.050034 59.92495 270)
			(size 0.519938 1.4986)
			(layers "F.Cu" "F.Mask" "F.Paste")
			(net "GND")
		)
		(pad "285" smd rect
			(at 2.050034 60.775088 270)
			(size 0.519938 1.4986)
			(layers "F.Cu" "F.Mask" "F.Paste")
			(net "M_G_CPU1_SB_DQ<30>")
		)
		(pad "286" smd rect
			(at 2.050034 61.624972 270)
			(size 0.519938 1.4986)
			(layers "F.Cu" "F.Mask" "F.Paste")
			(net "GND")
		)
		(pad "287" smd rect
			(at 2.050034 62.47511 270)
			(size 0.519938 1.4986)
			(layers "F.Cu" "F.Mask" "F.Paste")
			(net "M_G_CPU1_SB_DQ<31>")
		)
		(pad "288" smd rect
			(at 2.050034 63.324994 270)
			(size 0.519938 1.4986)
			(layers "F.Cu" "F.Mask" "F.Paste")
			(net "GND")
		)
		(pad "G1" thru_hole oval
			(at 0 -68.97497)
			(size 2.8194 1.5748)
			(drill oval 2.4384 1.1938)
			(layers "*.Cu" "*.Mask")
			(remove_unused_layers no)
			(net "GND")
			(clearance 0.127)
			(thermal_gap 0.127)
		)
		(pad "G2" thru_hole oval
			(at 0 3.875024)
			(size 2.8194 1.5748)
			(drill oval 2.4384 1.1938)
			(layers "*.Cu" "*.Mask")
			(remove_unused_layers no)
			(net "GND")
			(clearance 0.127)
			(thermal_gap 0.127)
		)
		(pad "G3" thru_hole oval
			(at 0 68.97497)
			(size 2.8194 1.5748)
			(drill oval 2.4384 1.1938)
			(layers "*.Cu" "*.Mask")
			(remove_unused_layers no)
			(net "GND")
			(clearance 0.127)
			(thermal_gap 0.127)
		)
	)
)
